FILE_TYPE = MACRO_DRAWING;
SET COLOR_WIRE YELLOW;
SET COLOR_PROP MONO;
SET COLOR_DOT WHITE;
SET COLOR_ARC YELLOW;
SET COLOR_BODY GREEN;
SET COLOR_NOTE MONO;
SET PROP_DISPLAY VALUE;
SET PAGE_NUMBER P29;
FORCEADD TAP..1
R 2
(-5425 3150);
FORCEPROP 3 LASTPIN (-5375 3150) SIG_NAME DMI_CPU0_PCH_RX_C_DN<2>
J 0
(-5365 3160);
DISPLAY 0.659574 (-5365 3160);
PAINT MONO (-5365 3160);
DISPLAY INVISIBLE (-5365 3160);
FORCEPROP 1 LASTPIN (-5375 3150) BN 2
J 2
(-5363 3158);
DISPLAY 0.617021 (-5363 3158);
PAINT PINK (-5363 3158);
FORCEPROP 2 LAST CDS_LIB mstr_standard
J 0
(-5425 3150);
PAINT MONO (-5425 3150);
DISPLAY INVISIBLE (-5425 3150);
FORCEPROP 1 LAST BODY_TYPE PLUMBING
J 2
(-5425 3200);
DISPLAY 1.446809 (-5425 3200);
PAINT GREEN (-5425 3200);
DISPLAY INVISIBLE (-5425 3200);
FORCEPROP 1 LAST HDL_TAP TRUE
J 2
(-5750 3025);
DISPLAY 1.446809 (-5750 3025);
PAINT GREEN (-5750 3025);
DISPLAY INVISIBLE (-5750 3025);
FORCEPROP 1 LAST PATH I10
J 2
(-5423 3150);
DISPLAY 0.872340 (-5423 3150);
PAINT GREEN (-5423 3150);
DISPLAY INVISIBLE (-5423 3150);
FORCEADD TAP..1
R 2
(-5425 3300);
FORCEPROP 3 LASTPIN (-5375 3300) SIG_NAME DMI_CPU0_PCH_RX_C_DP<0>
J 0
(-5365 3310);
DISPLAY 0.659574 (-5365 3310);
PAINT MONO (-5365 3310);
DISPLAY INVISIBLE (-5365 3310);
FORCEPROP 1 LASTPIN (-5375 3300) BN 0
J 2
(-5363 3308);
DISPLAY 0.617021 (-5363 3308);
PAINT PINK (-5363 3308);
FORCEPROP 2 LAST CDS_LIB mstr_standard
J 0
(-5425 3300);
PAINT MONO (-5425 3300);
DISPLAY INVISIBLE (-5425 3300);
FORCEPROP 1 LAST BODY_TYPE PLUMBING
J 2
(-5425 3350);
DISPLAY 1.446809 (-5425 3350);
PAINT GREEN (-5425 3350);
DISPLAY INVISIBLE (-5425 3350);
FORCEPROP 1 LAST HDL_TAP TRUE
J 2
(-5750 3175);
DISPLAY 1.446809 (-5750 3175);
PAINT GREEN (-5750 3175);
DISPLAY INVISIBLE (-5750 3175);
FORCEPROP 1 LAST PATH I11
J 2
(-5423 3300);
DISPLAY 0.872340 (-5423 3300);
PAINT GREEN (-5423 3300);
DISPLAY INVISIBLE (-5423 3300);
FORCEADD TAP..1
R 2
(-5425 3350);
FORCEPROP 3 LASTPIN (-5375 3350) SIG_NAME DMI_CPU0_PCH_RX_C_DP<1>
J 0
(-5365 3360);
DISPLAY 0.659574 (-5365 3360);
PAINT MONO (-5365 3360);
DISPLAY INVISIBLE (-5365 3360);
FORCEPROP 1 LASTPIN (-5375 3350) BN 1
J 2
(-5363 3358);
DISPLAY 0.617021 (-5363 3358);
PAINT PINK (-5363 3358);
FORCEPROP 2 LAST CDS_LIB mstr_standard
J 0
(-5425 3350);
PAINT MONO (-5425 3350);
DISPLAY INVISIBLE (-5425 3350);
FORCEPROP 1 LAST BODY_TYPE PLUMBING
J 2
(-5425 3400);
DISPLAY 1.446809 (-5425 3400);
PAINT GREEN (-5425 3400);
DISPLAY INVISIBLE (-5425 3400);
FORCEPROP 1 LAST HDL_TAP TRUE
J 2
(-5750 3225);
DISPLAY 1.446809 (-5750 3225);
PAINT GREEN (-5750 3225);
DISPLAY INVISIBLE (-5750 3225);
FORCEPROP 1 LAST PATH I12
J 2
(-5423 3350);
DISPLAY 0.872340 (-5423 3350);
PAINT GREEN (-5423 3350);
DISPLAY INVISIBLE (-5423 3350);
FORCEADD TAP..1
R 2
(-5425 3400);
FORCEPROP 3 LASTPIN (-5375 3400) SIG_NAME DMI_CPU0_PCH_RX_C_DP<2>
J 0
(-5365 3410);
DISPLAY 0.659574 (-5365 3410);
PAINT MONO (-5365 3410);
DISPLAY INVISIBLE (-5365 3410);
FORCEPROP 1 LASTPIN (-5375 3400) BN 2
J 2
(-5363 3408);
DISPLAY 0.617021 (-5363 3408);
PAINT PINK (-5363 3408);
FORCEPROP 2 LAST CDS_LIB mstr_standard
J 0
(-5425 3400);
PAINT MONO (-5425 3400);
DISPLAY INVISIBLE (-5425 3400);
FORCEPROP 1 LAST BODY_TYPE PLUMBING
J 2
(-5425 3450);
DISPLAY 1.446809 (-5425 3450);
PAINT GREEN (-5425 3450);
DISPLAY INVISIBLE (-5425 3450);
FORCEPROP 1 LAST HDL_TAP TRUE
J 2
(-5750 3275);
DISPLAY 1.446809 (-5750 3275);
PAINT GREEN (-5750 3275);
DISPLAY INVISIBLE (-5750 3275);
FORCEPROP 1 LAST PATH I13
J 2
(-5423 3400);
DISPLAY 0.872340 (-5423 3400);
PAINT GREEN (-5423 3400);
DISPLAY INVISIBLE (-5423 3400);
FORCEADD TAP..1
R 2
(-5425 3450);
FORCEPROP 3 LASTPIN (-5375 3450) SIG_NAME DMI_CPU0_PCH_RX_C_DP<3>
J 0
(-5365 3460);
DISPLAY 0.659574 (-5365 3460);
PAINT MONO (-5365 3460);
DISPLAY INVISIBLE (-5365 3460);
FORCEPROP 1 LASTPIN (-5375 3450) BN 3
J 2
(-5363 3458);
DISPLAY 0.617021 (-5363 3458);
PAINT PINK (-5363 3458);
FORCEPROP 2 LAST CDS_LIB mstr_standard
J 0
(-5425 3450);
PAINT MONO (-5425 3450);
DISPLAY INVISIBLE (-5425 3450);
FORCEPROP 1 LAST BODY_TYPE PLUMBING
J 2
(-5425 3500);
DISPLAY 1.446809 (-5425 3500);
PAINT GREEN (-5425 3500);
DISPLAY INVISIBLE (-5425 3500);
FORCEPROP 1 LAST HDL_TAP TRUE
J 2
(-5750 3325);
DISPLAY 1.446809 (-5750 3325);
PAINT GREEN (-5750 3325);
DISPLAY INVISIBLE (-5750 3325);
FORCEPROP 1 LAST PATH I14
J 2
(-5423 3450);
DISPLAY 0.872340 (-5423 3450);
PAINT GREEN (-5423 3450);
DISPLAY INVISIBLE (-5423 3450);
FORCEADD TAP..1
(-2350 3100);
FORCEPROP 3 LASTPIN (-2400 3100) SIG_NAME DMI_CPU0_PCH_TX_DN<1>
J 0
(-2390 3110);
DISPLAY 0.659574 (-2390 3110);
PAINT MONO (-2390 3110);
DISPLAY INVISIBLE (-2390 3110);
FORCEPROP 1 LASTPIN (-2400 3100) BN 1
J 0
(-2412 3108);
DISPLAY 0.617021 (-2412 3108);
PAINT PINK (-2412 3108);
FORCEPROP 2 LAST CDS_LIB mstr_standard
J 2
(-2350 3100);
PAINT MONO (-2350 3100);
DISPLAY INVISIBLE (-2350 3100);
FORCEPROP 1 LAST BODY_TYPE PLUMBING
J 0
(-2350 3150);
DISPLAY 1.446809 (-2350 3150);
PAINT GREEN (-2350 3150);
DISPLAY INVISIBLE (-2350 3150);
FORCEPROP 1 LAST HDL_TAP TRUE
J 0
(-2025 2975);
DISPLAY 1.446809 (-2025 2975);
PAINT GREEN (-2025 2975);
DISPLAY INVISIBLE (-2025 2975);
FORCEPROP 1 LAST PATH I16
J 0
(-2352 3100);
DISPLAY 0.872340 (-2352 3100);
PAINT GREEN (-2352 3100);
DISPLAY INVISIBLE (-2352 3100);
FORCEADD TAP..1
(-2350 3050);
FORCEPROP 3 LASTPIN (-2400 3050) SIG_NAME DMI_CPU0_PCH_TX_DN<0>
J 0
(-2390 3060);
DISPLAY 0.659574 (-2390 3060);
PAINT MONO (-2390 3060);
DISPLAY INVISIBLE (-2390 3060);
FORCEPROP 1 LASTPIN (-2400 3050) BN 0
J 0
(-2412 3058);
DISPLAY 0.617021 (-2412 3058);
PAINT PINK (-2412 3058);
FORCEPROP 2 LAST CDS_LIB mstr_standard
J 2
(-2350 3050);
PAINT MONO (-2350 3050);
DISPLAY INVISIBLE (-2350 3050);
FORCEPROP 1 LAST BODY_TYPE PLUMBING
J 0
(-2350 3100);
DISPLAY 1.446809 (-2350 3100);
PAINT GREEN (-2350 3100);
DISPLAY INVISIBLE (-2350 3100);
FORCEPROP 1 LAST HDL_TAP TRUE
J 0
(-2025 2925);
DISPLAY 1.446809 (-2025 2925);
PAINT GREEN (-2025 2925);
DISPLAY INVISIBLE (-2025 2925);
FORCEPROP 1 LAST PATH I17
J 0
(-2352 3050);
DISPLAY 0.872340 (-2352 3050);
PAINT GREEN (-2352 3050);
DISPLAY INVISIBLE (-2352 3050);
FORCEADD TAP..1
(-2350 3200);
FORCEPROP 3 LASTPIN (-2400 3200) SIG_NAME DMI_CPU0_PCH_TX_DN<3>
J 0
(-2390 3210);
DISPLAY 0.659574 (-2390 3210);
PAINT MONO (-2390 3210);
DISPLAY INVISIBLE (-2390 3210);
FORCEPROP 1 LASTPIN (-2400 3200) BN 3
J 0
(-2412 3208);
DISPLAY 0.617021 (-2412 3208);
PAINT PINK (-2412 3208);
FORCEPROP 2 LAST CDS_LIB mstr_standard
J 2
(-2350 3200);
PAINT MONO (-2350 3200);
DISPLAY INVISIBLE (-2350 3200);
FORCEPROP 1 LAST BODY_TYPE PLUMBING
J 0
(-2350 3250);
DISPLAY 1.446809 (-2350 3250);
PAINT GREEN (-2350 3250);
DISPLAY INVISIBLE (-2350 3250);
FORCEPROP 1 LAST HDL_TAP TRUE
J 0
(-2025 3075);
DISPLAY 1.446809 (-2025 3075);
PAINT GREEN (-2025 3075);
DISPLAY INVISIBLE (-2025 3075);
FORCEPROP 1 LAST PATH I18
J 0
(-2352 3200);
DISPLAY 0.872340 (-2352 3200);
PAINT GREEN (-2352 3200);
DISPLAY INVISIBLE (-2352 3200);
FORCEADD TAP..1
(-2350 3150);
FORCEPROP 3 LASTPIN (-2400 3150) SIG_NAME DMI_CPU0_PCH_TX_DN<2>
J 0
(-2390 3160);
DISPLAY 0.659574 (-2390 3160);
PAINT MONO (-2390 3160);
DISPLAY INVISIBLE (-2390 3160);
FORCEPROP 1 LASTPIN (-2400 3150) BN 2
J 0
(-2412 3158);
DISPLAY 0.617021 (-2412 3158);
PAINT PINK (-2412 3158);
FORCEPROP 2 LAST CDS_LIB mstr_standard
J 2
(-2350 3150);
PAINT MONO (-2350 3150);
DISPLAY INVISIBLE (-2350 3150);
FORCEPROP 1 LAST BODY_TYPE PLUMBING
J 0
(-2350 3200);
DISPLAY 1.446809 (-2350 3200);
PAINT GREEN (-2350 3200);
DISPLAY INVISIBLE (-2350 3200);
FORCEPROP 1 LAST HDL_TAP TRUE
J 0
(-2025 3025);
DISPLAY 1.446809 (-2025 3025);
PAINT GREEN (-2025 3025);
DISPLAY INVISIBLE (-2025 3025);
FORCEPROP 1 LAST PATH I19
J 0
(-2352 3150);
DISPLAY 0.872340 (-2352 3150);
PAINT GREEN (-2352 3150);
DISPLAY INVISIBLE (-2352 3150);
FORCEADD TAP..1
(-2350 3300);
FORCEPROP 3 LASTPIN (-2400 3300) SIG_NAME DMI_CPU0_PCH_TX_DP<0>
J 0
(-2390 3310);
DISPLAY 0.659574 (-2390 3310);
PAINT MONO (-2390 3310);
DISPLAY INVISIBLE (-2390 3310);
FORCEPROP 1 LASTPIN (-2400 3300) BN 0
J 0
(-2412 3308);
DISPLAY 0.617021 (-2412 3308);
PAINT PINK (-2412 3308);
FORCEPROP 2 LAST CDS_LIB mstr_standard
J 2
(-2350 3300);
PAINT MONO (-2350 3300);
DISPLAY INVISIBLE (-2350 3300);
FORCEPROP 1 LAST BODY_TYPE PLUMBING
J 0
(-2350 3350);
DISPLAY 1.446809 (-2350 3350);
PAINT GREEN (-2350 3350);
DISPLAY INVISIBLE (-2350 3350);
FORCEPROP 1 LAST HDL_TAP TRUE
J 0
(-2025 3175);
DISPLAY 1.446809 (-2025 3175);
PAINT GREEN (-2025 3175);
DISPLAY INVISIBLE (-2025 3175);
FORCEPROP 1 LAST PATH I20
J 0
(-2352 3300);
DISPLAY 0.872340 (-2352 3300);
PAINT GREEN (-2352 3300);
DISPLAY INVISIBLE (-2352 3300);
FORCEADD TAP..1
(-2350 3400);
FORCEPROP 3 LASTPIN (-2400 3400) SIG_NAME DMI_CPU0_PCH_TX_DP<2>
J 0
(-2390 3410);
DISPLAY 0.659574 (-2390 3410);
PAINT MONO (-2390 3410);
DISPLAY INVISIBLE (-2390 3410);
FORCEPROP 1 LASTPIN (-2400 3400) BN 2
J 0
(-2412 3408);
DISPLAY 0.617021 (-2412 3408);
PAINT PINK (-2412 3408);
FORCEPROP 2 LAST CDS_LIB mstr_standard
J 2
(-2350 3400);
PAINT MONO (-2350 3400);
DISPLAY INVISIBLE (-2350 3400);
FORCEPROP 1 LAST BODY_TYPE PLUMBING
J 0
(-2350 3450);
DISPLAY 1.446809 (-2350 3450);
PAINT GREEN (-2350 3450);
DISPLAY INVISIBLE (-2350 3450);
FORCEPROP 1 LAST HDL_TAP TRUE
J 0
(-2025 3275);
DISPLAY 1.446809 (-2025 3275);
PAINT GREEN (-2025 3275);
DISPLAY INVISIBLE (-2025 3275);
FORCEPROP 1 LAST PATH I21
J 0
(-2352 3400);
DISPLAY 0.872340 (-2352 3400);
PAINT GREEN (-2352 3400);
DISPLAY INVISIBLE (-2352 3400);
FORCEADD TAP..1
(-2350 3350);
FORCEPROP 3 LASTPIN (-2400 3350) SIG_NAME DMI_CPU0_PCH_TX_DP<1>
J 0
(-2390 3360);
DISPLAY 0.659574 (-2390 3360);
PAINT MONO (-2390 3360);
DISPLAY INVISIBLE (-2390 3360);
FORCEPROP 1 LASTPIN (-2400 3350) BN 1
J 0
(-2412 3358);
DISPLAY 0.617021 (-2412 3358);
PAINT PINK (-2412 3358);
FORCEPROP 2 LAST CDS_LIB mstr_standard
J 2
(-2350 3350);
PAINT MONO (-2350 3350);
DISPLAY INVISIBLE (-2350 3350);
FORCEPROP 1 LAST BODY_TYPE PLUMBING
J 0
(-2350 3400);
DISPLAY 1.446809 (-2350 3400);
PAINT GREEN (-2350 3400);
DISPLAY INVISIBLE (-2350 3400);
FORCEPROP 1 LAST HDL_TAP TRUE
J 0
(-2025 3225);
DISPLAY 1.446809 (-2025 3225);
PAINT GREEN (-2025 3225);
DISPLAY INVISIBLE (-2025 3225);
FORCEPROP 1 LAST PATH I22
J 0
(-2352 3350);
DISPLAY 0.872340 (-2352 3350);
PAINT GREEN (-2352 3350);
DISPLAY INVISIBLE (-2352 3350);
FORCEADD TAP..1
(-2350 3450);
FORCEPROP 3 LASTPIN (-2400 3450) SIG_NAME DMI_CPU0_PCH_TX_DP<3>
J 0
(-2390 3460);
DISPLAY 0.659574 (-2390 3460);
PAINT MONO (-2390 3460);
DISPLAY INVISIBLE (-2390 3460);
FORCEPROP 1 LASTPIN (-2400 3450) BN 3
J 0
(-2412 3458);
DISPLAY 0.617021 (-2412 3458);
PAINT PINK (-2412 3458);
FORCEPROP 2 LAST CDS_LIB mstr_standard
J 2
(-2350 3450);
PAINT MONO (-2350 3450);
DISPLAY INVISIBLE (-2350 3450);
FORCEPROP 1 LAST BODY_TYPE PLUMBING
J 0
(-2350 3500);
DISPLAY 1.446809 (-2350 3500);
PAINT GREEN (-2350 3500);
DISPLAY INVISIBLE (-2350 3500);
FORCEPROP 1 LAST HDL_TAP TRUE
J 0
(-2025 3325);
DISPLAY 1.446809 (-2025 3325);
PAINT GREEN (-2025 3325);
DISPLAY INVISIBLE (-2025 3325);
FORCEPROP 1 LAST PATH I23
J 0
(-2352 3450);
DISPLAY 0.872340 (-2352 3450);
PAINT GREEN (-2352 3450);
DISPLAY INVISIBLE (-2352 3450);
FORCEADD OFFPAGE..2
(-1000 3225);
FORCEPROP 2 LAST $XR0 129 
J 0
(-811 3225);
DISPLAY 0.638298 (-811 3225);
PAINT MONO (-811 3225);
FORCEPROP 2 LAST CDS_LIB mstr_standard
J 0
(-1000 3225);
PAINT MONO (-1000 3225);
DISPLAY INVISIBLE (-1000 3225);
FORCEPROP 1 LAST OFFPAGE TRUE
J 0
(-675 3100);
DISPLAY 1.170213 (-675 3100);
PAINT GREEN (-675 3100);
DISPLAY INVISIBLE (-675 3100);
FORCEPROP 1 LAST COMMENT_BODY TRUE
J 0
(-1045 3130);
DISPLAY 1.170213 (-1045 3130);
PAINT GREEN (-1045 3130);
DISPLAY INVISIBLE (-1045 3130);
FORCEPROP 2 LAST PATH I25
J 0
(-825 3300);
DISPLAY 1.021277 (-825 3300);
PAINT ORANGE (-825 3300);
DISPLAY INVISIBLE (-825 3300);
FORCEADD OFFPAGE..2
(-1000 3475);
FORCEPROP 2 LAST $XR0 129 
J 0
(-811 3475);
DISPLAY 0.638298 (-811 3475);
PAINT MONO (-811 3475);
FORCEPROP 2 LAST CDS_LIB mstr_standard
J 0
(-1000 3475);
PAINT MONO (-1000 3475);
DISPLAY INVISIBLE (-1000 3475);
FORCEPROP 1 LAST OFFPAGE TRUE
J 0
(-675 3350);
DISPLAY 1.170213 (-675 3350);
PAINT GREEN (-675 3350);
DISPLAY INVISIBLE (-675 3350);
FORCEPROP 1 LAST COMMENT_BODY TRUE
J 0
(-1045 3380);
DISPLAY 1.170213 (-1045 3380);
PAINT GREEN (-1045 3380);
DISPLAY INVISIBLE (-1045 3380);
FORCEPROP 2 LAST PATH I26
J 0
(-825 3550);
DISPLAY 1.021277 (-825 3550);
PAINT ORANGE (-825 3550);
DISPLAY INVISIBLE (-825 3550);
FORCEADD OFFPAGE..1
(-6150 2400);
FORCEPROP 2 LAST $XR0 113 
J 0
(-6402 2400);
DISPLAY 0.638298 (-6402 2400);
PAINT MONO (-6402 2400);
FORCEPROP 2 LAST $XR1 63 
J 0
(-6492 2400);
DISPLAY 0.638298 (-6492 2400);
PAINT MONO (-6492 2400);
FORCEPROP 2 LAST CDS_LIB mstr_standard
J 0
(-6150 2400);
PAINT ORANGE (-6150 2400);
DISPLAY INVISIBLE (-6150 2400);
FORCEPROP 1 LAST OFFPAGE TRUE
J 0
(-5825 2275);
DISPLAY 0.872340 (-5825 2275);
PAINT GREEN (-5825 2275);
DISPLAY INVISIBLE (-5825 2275);
FORCEPROP 1 LAST COMMENT_BODY TRUE
J 0
(-6025 2300);
DISPLAY 0.872340 (-6025 2300);
PAINT GREEN (-6025 2300);
DISPLAY INVISIBLE (-6025 2300);
FORCEPROP 2 LAST PATH I27
J 0
(-6100 2475);
DISPLAY 1.021277 (-6100 2475);
PAINT ORANGE (-6100 2475);
DISPLAY INVISIBLE (-6100 2475);
FORCEADD OFFPAGE..1
(-6150 2350);
FORCEPROP 2 LAST $XR0 113 
J 0
(-6402 2350);
DISPLAY 0.638298 (-6402 2350);
PAINT MONO (-6402 2350);
FORCEPROP 2 LAST CDS_LIB mstr_standard
J 0
(-6150 2350);
PAINT ORANGE (-6150 2350);
DISPLAY INVISIBLE (-6150 2350);
FORCEPROP 1 LAST OFFPAGE TRUE
J 0
(-5825 2225);
DISPLAY 1.170213 (-5825 2225);
PAINT GREEN (-5825 2225);
DISPLAY INVISIBLE (-5825 2225);
FORCEPROP 1 LAST COMMENT_BODY TRUE
J 0
(-6025 2250);
DISPLAY 1.170213 (-6025 2250);
PAINT GREEN (-6025 2250);
DISPLAY INVISIBLE (-6025 2250);
FORCEPROP 2 LAST PATH I28
J 0
(-6100 2425);
DISPLAY 1.021277 (-6100 2425);
PAINT ORANGE (-6100 2425);
DISPLAY INVISIBLE (-6100 2425);
FORCEADD OFFPAGE..1
(-6150 2300);
FORCEPROP 2 LAST $XR0 113 
J 0
(-6402 2300);
DISPLAY 0.638298 (-6402 2300);
PAINT MONO (-6402 2300);
FORCEPROP 2 LAST $XR1 63 
J 0
(-6492 2300);
DISPLAY 0.638298 (-6492 2300);
PAINT MONO (-6492 2300);
FORCEPROP 2 LAST CDS_LIB mstr_standard
J 0
(-6150 2300);
PAINT ORANGE (-6150 2300);
DISPLAY INVISIBLE (-6150 2300);
FORCEPROP 1 LAST OFFPAGE TRUE
J 0
(-5825 2175);
DISPLAY 0.872340 (-5825 2175);
PAINT GREEN (-5825 2175);
DISPLAY INVISIBLE (-5825 2175);
FORCEPROP 1 LAST COMMENT_BODY TRUE
J 0
(-6025 2200);
DISPLAY 0.872340 (-6025 2200);
PAINT GREEN (-6025 2200);
DISPLAY INVISIBLE (-6025 2200);
FORCEPROP 2 LAST PATH I29
J 0
(-6100 2375);
DISPLAY 1.021277 (-6100 2375);
PAINT ORANGE (-6100 2375);
DISPLAY INVISIBLE (-6100 2375);
FORCEADD OFFPAGE..2
(-1825 2250);
FORCEPROP 2 LAST $XR0 113 
J 0
(-1636 2250);
DISPLAY 0.638298 (-1636 2250);
PAINT MONO (-1636 2250);
FORCEPROP 2 LAST CDS_LIB mstr_standard
J 0
(-1825 2250);
PAINT ORANGE (-1825 2250);
DISPLAY INVISIBLE (-1825 2250);
FORCEPROP 1 LAST OFFPAGE TRUE
J 0
(-1500 2125);
DISPLAY 1.170213 (-1500 2125);
PAINT GREEN (-1500 2125);
DISPLAY INVISIBLE (-1500 2125);
FORCEPROP 1 LAST COMMENT_BODY TRUE
J 0
(-1870 2155);
DISPLAY 1.170213 (-1870 2155);
PAINT GREEN (-1870 2155);
DISPLAY INVISIBLE (-1870 2155);
FORCEPROP 2 LAST PATH I31
J 0
(-1650 2325);
DISPLAY 1.021277 (-1650 2325);
PAINT ORANGE (-1650 2325);
DISPLAY INVISIBLE (-1650 2325);
FORCEADD OFFPAGE..1
R 2
(-1800 2950);
FORCEPROP 2 LAST $XR0 103 
J 0
(-1614 2950);
DISPLAY 0.638298 (-1614 2950);
PAINT MONO (-1614 2950);
FORCEPROP 2 LAST CDS_LIB mstr_standard
J 0
(-1800 2950);
PAINT ORANGE (-1800 2950);
DISPLAY INVISIBLE (-1800 2950);
FORCEPROP 1 LAST OFFPAGE TRUE
J 2
(-2125 2825);
DISPLAY 0.872340 (-2125 2825);
PAINT GREEN (-2125 2825);
DISPLAY INVISIBLE (-2125 2825);
FORCEPROP 1 LAST COMMENT_BODY TRUE
J 2
(-1925 2850);
DISPLAY 0.872340 (-1925 2850);
PAINT GREEN (-1925 2850);
DISPLAY INVISIBLE (-1925 2850);
FORCEPROP 2 LAST PATH I35
J 0
(-1625 3025);
DISPLAY 1.021277 (-1625 3025);
PAINT ORANGE (-1625 3025);
DISPLAY INVISIBLE (-1625 3025);
FORCEADD OFFPAGE..1
R 2
(-1800 2900);
FORCEPROP 2 LAST $XR0 103 
J 0
(-1614 2900);
DISPLAY 0.638298 (-1614 2900);
PAINT MONO (-1614 2900);
FORCEPROP 2 LAST CDS_LIB mstr_standard
J 0
(-1800 2900);
PAINT ORANGE (-1800 2900);
DISPLAY INVISIBLE (-1800 2900);
FORCEPROP 1 LAST OFFPAGE TRUE
J 2
(-2125 2775);
DISPLAY 0.872340 (-2125 2775);
PAINT GREEN (-2125 2775);
DISPLAY INVISIBLE (-2125 2775);
FORCEPROP 1 LAST COMMENT_BODY TRUE
J 2
(-1925 2800);
DISPLAY 0.872340 (-1925 2800);
PAINT GREEN (-1925 2800);
DISPLAY INVISIBLE (-1925 2800);
FORCEPROP 2 LAST PATH I36
J 0
(-1625 2975);
DISPLAY 1.021277 (-1625 2975);
PAINT ORANGE (-1625 2975);
DISPLAY INVISIBLE (-1625 2975);
FORCEADD OFFPAGE..1
(-6150 2950);
FORCEPROP 2 LAST $XR0 104 
J 0
(-6402 2950);
DISPLAY 0.638298 (-6402 2950);
PAINT MONO (-6402 2950);
FORCEPROP 2 LAST CDS_LIB mstr_standard
J 0
(-6150 2950);
PAINT ORANGE (-6150 2950);
DISPLAY INVISIBLE (-6150 2950);
FORCEPROP 1 LAST OFFPAGE TRUE
J 0
(-5825 2825);
DISPLAY 0.872340 (-5825 2825);
PAINT GREEN (-5825 2825);
DISPLAY INVISIBLE (-5825 2825);
FORCEPROP 1 LAST COMMENT_BODY TRUE
J 0
(-6025 2850);
DISPLAY 0.872340 (-6025 2850);
PAINT GREEN (-6025 2850);
DISPLAY INVISIBLE (-6025 2850);
FORCEPROP 2 LAST PATH I40
J 0
(-6100 3025);
DISPLAY 1.021277 (-6100 3025);
PAINT ORANGE (-6100 3025);
DISPLAY INVISIBLE (-6100 3025);
FORCEADD OFFPAGE..1
(-6150 2900);
FORCEPROP 2 LAST $XR0 104 
J 0
(-6402 2900);
DISPLAY 0.638298 (-6402 2900);
PAINT MONO (-6402 2900);
FORCEPROP 2 LAST CDS_LIB mstr_standard
J 0
(-6150 2900);
PAINT ORANGE (-6150 2900);
DISPLAY INVISIBLE (-6150 2900);
FORCEPROP 1 LAST OFFPAGE TRUE
J 0
(-5825 2775);
DISPLAY 0.872340 (-5825 2775);
PAINT GREEN (-5825 2775);
DISPLAY INVISIBLE (-5825 2775);
FORCEPROP 1 LAST COMMENT_BODY TRUE
J 0
(-6025 2800);
DISPLAY 0.872340 (-6025 2800);
PAINT GREEN (-6025 2800);
DISPLAY INVISIBLE (-6025 2800);
FORCEPROP 2 LAST PATH I41
J 0
(-6100 2975);
DISPLAY 1.021277 (-6100 2975);
PAINT ORANGE (-6100 2975);
DISPLAY INVISIBLE (-6100 2975);
FORCEADD OFFPAGE..1
R 2
(-1850 2350);
FORCEPROP 2 LAST $XR0 190 
J 0
(-1664 2350);
DISPLAY 0.638298 (-1664 2350);
PAINT MONO (-1664 2350);
FORCEPROP 2 LAST $XR1 192 
J 0
(-1544 2350);
DISPLAY 0.638298 (-1544 2350);
PAINT MONO (-1544 2350);
FORCEPROP 2 LAST CDS_LIB mstr_standard
J 0
(-1850 2350);
PAINT MONO (-1850 2350);
DISPLAY INVISIBLE (-1850 2350);
FORCEPROP 1 LAST OFFPAGE TRUE
J 2
(-2175 2225);
DISPLAY 0.872340 (-2175 2225);
PAINT GREEN (-2175 2225);
DISPLAY INVISIBLE (-2175 2225);
FORCEPROP 1 LAST COMMENT_BODY TRUE
J 2
(-1975 2250);
DISPLAY 0.872340 (-1975 2250);
PAINT GREEN (-1975 2250);
DISPLAY INVISIBLE (-1975 2250);
FORCEPROP 2 LAST PATH I42
J 0
(-1675 2425);
DISPLAY 1.021277 (-1675 2425);
PAINT ORANGE (-1675 2425);
DISPLAY INVISIBLE (-1675 2425);
FORCEADD OFFPAGE..5
(-6175 2800);
FORCEPROP 2 LAST $XR0 91 
J 0
(-6429 2800);
DISPLAY 0.638298 (-6429 2800);
PAINT MONO (-6429 2800);
FORCEPROP 2 LAST CDS_LIB mstr_standard
J 0
(-6175 2800);
PAINT MONO (-6175 2800);
DISPLAY INVISIBLE (-6175 2800);
FORCEPROP 1 LAST OFFPAGE TRUE
J 0
(-5850 2675);
DISPLAY 0.872340 (-5850 2675);
PAINT GREEN (-5850 2675);
DISPLAY INVISIBLE (-5850 2675);
FORCEPROP 1 LAST COMMENT_BODY TRUE
J 0
(-6075 2725);
DISPLAY 0.872340 (-6075 2725);
PAINT GREEN (-6075 2725);
DISPLAY INVISIBLE (-6075 2725);
FORCEPROP 2 LAST PATH I43
J 0
(-6125 2875);
DISPLAY 1.021277 (-6125 2875);
PAINT ORANGE (-6125 2875);
DISPLAY INVISIBLE (-6125 2875);
FORCEADD OFFPAGE..1
(-6175 2750);
FORCEPROP 2 LAST $XR0 91 
J 0
(-6426 2750);
DISPLAY 0.638298 (-6426 2750);
PAINT MONO (-6426 2750);
FORCEPROP 2 LAST CDS_LIB mstr_standard
J 0
(-6175 2750);
PAINT MONO (-6175 2750);
DISPLAY INVISIBLE (-6175 2750);
FORCEPROP 1 LAST OFFPAGE TRUE
J 0
(-5850 2625);
DISPLAY 0.872340 (-5850 2625);
PAINT GREEN (-5850 2625);
DISPLAY INVISIBLE (-5850 2625);
FORCEPROP 1 LAST COMMENT_BODY TRUE
J 0
(-6050 2650);
DISPLAY 0.872340 (-6050 2650);
PAINT GREEN (-6050 2650);
DISPLAY INVISIBLE (-6050 2650);
FORCEPROP 2 LAST PATH I44
J 0
(-6125 2825);
DISPLAY 1.021277 (-6125 2825);
PAINT ORANGE (-6125 2825);
DISPLAY INVISIBLE (-6125 2825);
FORCEADD OFFPAGE..1
(-6175 2650);
FORCEPROP 2 LAST $XR0 91 
J 0
(-6426 2650);
DISPLAY 0.638298 (-6426 2650);
PAINT MONO (-6426 2650);
FORCEPROP 2 LAST CDS_LIB mstr_standard
J 0
(-6175 2650);
PAINT MONO (-6175 2650);
DISPLAY INVISIBLE (-6175 2650);
FORCEPROP 1 LAST OFFPAGE TRUE
J 0
(-5850 2525);
DISPLAY 0.872340 (-5850 2525);
PAINT GREEN (-5850 2525);
DISPLAY INVISIBLE (-5850 2525);
FORCEPROP 1 LAST COMMENT_BODY TRUE
J 0
(-6050 2550);
DISPLAY 0.872340 (-6050 2550);
PAINT GREEN (-6050 2550);
DISPLAY INVISIBLE (-6050 2550);
FORCEPROP 2 LAST PATH I45
J 0
(-6125 2725);
DISPLAY 1.021277 (-6125 2725);
PAINT ORANGE (-6125 2725);
DISPLAY INVISIBLE (-6125 2725);
FORCEADD OFFPAGE..5
(-6175 2700);
FORCEPROP 2 LAST $XR0 91 
J 0
(-6429 2700);
DISPLAY 0.638298 (-6429 2700);
PAINT MONO (-6429 2700);
FORCEPROP 2 LAST CDS_LIB mstr_standard
J 0
(-6175 2700);
PAINT MONO (-6175 2700);
DISPLAY INVISIBLE (-6175 2700);
FORCEPROP 1 LAST OFFPAGE TRUE
J 0
(-5850 2575);
DISPLAY 0.872340 (-5850 2575);
PAINT GREEN (-5850 2575);
DISPLAY INVISIBLE (-5850 2575);
FORCEPROP 1 LAST COMMENT_BODY TRUE
J 0
(-6075 2625);
DISPLAY 0.872340 (-6075 2625);
PAINT GREEN (-6075 2625);
DISPLAY INVISIBLE (-6075 2625);
FORCEPROP 2 LAST PATH I46
J 0
(-6125 2775);
DISPLAY 1.021277 (-6125 2775);
PAINT ORANGE (-6125 2775);
DISPLAY INVISIBLE (-6125 2775);
FORCEADD OFFPAGE..5
(-6175 2550);
FORCEPROP 2 LAST $XR0 91 
J 0
(-6429 2550);
DISPLAY 0.638298 (-6429 2550);
PAINT MONO (-6429 2550);
FORCEPROP 2 LAST CDS_LIB mstr_standard
J 0
(-6175 2550);
PAINT MONO (-6175 2550);
DISPLAY INVISIBLE (-6175 2550);
FORCEPROP 1 LAST OFFPAGE TRUE
J 0
(-5850 2425);
DISPLAY 0.872340 (-5850 2425);
PAINT GREEN (-5850 2425);
DISPLAY INVISIBLE (-5850 2425);
FORCEPROP 1 LAST COMMENT_BODY TRUE
J 0
(-6075 2475);
DISPLAY 0.872340 (-6075 2475);
PAINT GREEN (-6075 2475);
DISPLAY INVISIBLE (-6075 2475);
FORCEPROP 2 LAST PATH I47
J 0
(-6125 2625);
DISPLAY 1.021277 (-6125 2625);
PAINT ORANGE (-6125 2625);
DISPLAY INVISIBLE (-6125 2625);
FORCEADD OFFPAGE..3
R 2
(-6175 2500);
FORCEPROP 2 LAST $XR0 91 
J 0
(-6454 2500);
DISPLAY 0.638298 (-6454 2500);
PAINT MONO (-6454 2500);
FORCEPROP 2 LAST CDS_LIB mstr_standard
J 2
(-6175 2500);
PAINT MONO (-6175 2500);
DISPLAY INVISIBLE (-6175 2500);
FORCEPROP 1 LAST OFFPAGE TRUE
J 2
(-6500 2375);
DISPLAY 0.872340 (-6500 2375);
PAINT GREEN (-6500 2375);
DISPLAY INVISIBLE (-6500 2375);
FORCEPROP 1 LAST COMMENT_BODY TRUE
J 2
(-6125 2400);
DISPLAY 0.872340 (-6125 2400);
PAINT GREEN (-6125 2400);
DISPLAY INVISIBLE (-6125 2400);
FORCEPROP 2 LAST PATH I48
J 2
(-6225 2575);
DISPLAY 1.021277 (-6225 2575);
PAINT ORANGE (-6225 2575);
DISPLAY INVISIBLE (-6225 2575);
FORCEADD OFFPAGE..1
R 2
(-1800 2750);
FORCEPROP 2 LAST $XR0 91 
J 0
(-1614 2750);
DISPLAY 0.638298 (-1614 2750);
PAINT MONO (-1614 2750);
FORCEPROP 2 LAST CDS_LIB mstr_standard
J 0
(-1800 2750);
PAINT MONO (-1800 2750);
DISPLAY INVISIBLE (-1800 2750);
FORCEPROP 1 LAST OFFPAGE TRUE
J 2
(-2125 2625);
DISPLAY 0.872340 (-2125 2625);
PAINT GREEN (-2125 2625);
DISPLAY INVISIBLE (-2125 2625);
FORCEPROP 1 LAST COMMENT_BODY TRUE
J 2
(-1925 2650);
DISPLAY 0.872340 (-1925 2650);
PAINT GREEN (-1925 2650);
DISPLAY INVISIBLE (-1925 2650);
FORCEPROP 2 LAST PATH I49
J 0
(-1625 2825);
DISPLAY 1.021277 (-1625 2825);
PAINT ORANGE (-1625 2825);
DISPLAY INVISIBLE (-1625 2825);
FORCEADD OFFPAGE..1
(-6800 3225);
FORCEPROP 2 LAST $XR0 129 
J 0
(-7052 3225);
DISPLAY 0.638298 (-7052 3225);
PAINT MONO (-7052 3225);
FORCEPROP 2 LAST CDS_LIB mstr_standard
J 0
(-6800 3225);
PAINT MONO (-6800 3225);
DISPLAY INVISIBLE (-6800 3225);
FORCEPROP 1 LAST OFFPAGE TRUE
J 0
(-6475 3100);
DISPLAY 1.170213 (-6475 3100);
PAINT GREEN (-6475 3100);
DISPLAY INVISIBLE (-6475 3100);
FORCEPROP 1 LAST COMMENT_BODY TRUE
J 0
(-6675 3125);
DISPLAY 1.170213 (-6675 3125);
PAINT GREEN (-6675 3125);
DISPLAY INVISIBLE (-6675 3125);
FORCEPROP 2 LAST PATH I5
J 0
(-6750 3300);
DISPLAY 1.021277 (-6750 3300);
PAINT ORANGE (-6750 3300);
DISPLAY INVISIBLE (-6750 3300);
FORCEADD OFFPAGE..1
R 2
(-1800 2650);
FORCEPROP 2 LAST $XR0 91 
J 0
(-1614 2650);
DISPLAY 0.638298 (-1614 2650);
PAINT MONO (-1614 2650);
FORCEPROP 2 LAST CDS_LIB mstr_standard
J 0
(-1800 2650);
PAINT MONO (-1800 2650);
DISPLAY INVISIBLE (-1800 2650);
FORCEPROP 1 LAST OFFPAGE TRUE
J 2
(-2125 2525);
DISPLAY 0.872340 (-2125 2525);
PAINT GREEN (-2125 2525);
DISPLAY INVISIBLE (-2125 2525);
FORCEPROP 1 LAST COMMENT_BODY TRUE
J 2
(-1925 2550);
DISPLAY 0.872340 (-1925 2550);
PAINT GREEN (-1925 2550);
DISPLAY INVISIBLE (-1925 2550);
FORCEPROP 2 LAST PATH I50
J 0
(-1625 2725);
DISPLAY 1.021277 (-1625 2725);
PAINT ORANGE (-1625 2725);
DISPLAY INVISIBLE (-1625 2725);
FORCEADD OFFPAGE..2
(-1800 2800);
FORCEPROP 2 LAST $XR0 91 
J 0
(-1611 2800);
DISPLAY 0.638298 (-1611 2800);
PAINT MONO (-1611 2800);
FORCEPROP 2 LAST CDS_LIB mstr_standard
J 0
(-1800 2800);
PAINT MONO (-1800 2800);
DISPLAY INVISIBLE (-1800 2800);
FORCEPROP 1 LAST OFFPAGE TRUE
J 0
(-1475 2675);
DISPLAY 1.170213 (-1475 2675);
PAINT GREEN (-1475 2675);
DISPLAY INVISIBLE (-1475 2675);
FORCEPROP 1 LAST COMMENT_BODY TRUE
J 0
(-1845 2705);
DISPLAY 1.170213 (-1845 2705);
PAINT GREEN (-1845 2705);
DISPLAY INVISIBLE (-1845 2705);
FORCEPROP 2 LAST PATH I51
J 0
(-1625 2875);
DISPLAY 1.021277 (-1625 2875);
PAINT ORANGE (-1625 2875);
DISPLAY INVISIBLE (-1625 2875);
FORCEADD OFFPAGE..2
(-1800 2700);
FORCEPROP 2 LAST $XR0 91 
J 0
(-1611 2700);
DISPLAY 0.638298 (-1611 2700);
PAINT MONO (-1611 2700);
FORCEPROP 2 LAST CDS_LIB mstr_standard
J 0
(-1800 2700);
PAINT MONO (-1800 2700);
DISPLAY INVISIBLE (-1800 2700);
FORCEPROP 1 LAST OFFPAGE TRUE
J 0
(-1475 2575);
DISPLAY 1.170213 (-1475 2575);
PAINT GREEN (-1475 2575);
DISPLAY INVISIBLE (-1475 2575);
FORCEPROP 1 LAST COMMENT_BODY TRUE
J 0
(-1845 2605);
DISPLAY 1.170213 (-1845 2605);
PAINT GREEN (-1845 2605);
DISPLAY INVISIBLE (-1845 2605);
FORCEPROP 2 LAST PATH I52
J 0
(-1625 2775);
DISPLAY 1.021277 (-1625 2775);
PAINT ORANGE (-1625 2775);
DISPLAY INVISIBLE (-1625 2775);
FORCEADD OFFPAGE..2
(-1800 2550);
FORCEPROP 2 LAST $XR0 91 
J 0
(-1611 2550);
DISPLAY 0.638298 (-1611 2550);
PAINT MONO (-1611 2550);
FORCEPROP 2 LAST CDS_LIB mstr_standard
J 0
(-1800 2550);
PAINT MONO (-1800 2550);
DISPLAY INVISIBLE (-1800 2550);
FORCEPROP 1 LAST OFFPAGE TRUE
J 0
(-1475 2425);
DISPLAY 1.170213 (-1475 2425);
PAINT GREEN (-1475 2425);
DISPLAY INVISIBLE (-1475 2425);
FORCEPROP 1 LAST COMMENT_BODY TRUE
J 0
(-1845 2455);
DISPLAY 1.170213 (-1845 2455);
PAINT GREEN (-1845 2455);
DISPLAY INVISIBLE (-1845 2455);
FORCEPROP 2 LAST PATH I53
J 0
(-1625 2625);
DISPLAY 1.021277 (-1625 2625);
PAINT ORANGE (-1625 2625);
DISPLAY INVISIBLE (-1625 2625);
FORCEADD OFFPAGE..3
(-1800 2500);
FORCEPROP 2 LAST $XR0 91 
J 0
(-1586 2500);
DISPLAY 0.638298 (-1586 2500);
PAINT MONO (-1586 2500);
FORCEPROP 2 LAST CDS_LIB mstr_standard
J 0
(-1800 2500);
PAINT MONO (-1800 2500);
DISPLAY INVISIBLE (-1800 2500);
FORCEPROP 1 LAST OFFPAGE TRUE
J 0
(-1475 2375);
DISPLAY 0.872340 (-1475 2375);
PAINT GREEN (-1475 2375);
DISPLAY INVISIBLE (-1475 2375);
FORCEPROP 1 LAST COMMENT_BODY TRUE
J 0
(-1850 2400);
DISPLAY 0.872340 (-1850 2400);
PAINT GREEN (-1850 2400);
DISPLAY INVISIBLE (-1850 2400);
FORCEPROP 2 LAST PATH I54
J 0
(-1625 2575);
DISPLAY 1.021277 (-1625 2575);
PAINT ORANGE (-1625 2575);
DISPLAY INVISIBLE (-1625 2575);
FORCEADD OFFPAGE..1
(-6150 2250);
FORCEPROP 2 LAST $XR0 113 
J 0
(-6402 2250);
DISPLAY 0.638298 (-6402 2250);
PAINT MONO (-6402 2250);
FORCEPROP 2 LAST $XR1 63 
J 0
(-6492 2250);
DISPLAY 0.638298 (-6492 2250);
PAINT MONO (-6492 2250);
FORCEPROP 2 LAST CDS_LIB mstr_standard
J 0
(-6150 2250);
PAINT MONO (-6150 2250);
DISPLAY INVISIBLE (-6150 2250);
FORCEPROP 1 LAST OFFPAGE TRUE
J 0
(-5825 2125);
DISPLAY 0.872340 (-5825 2125);
PAINT GREEN (-5825 2125);
DISPLAY INVISIBLE (-5825 2125);
FORCEPROP 1 LAST COMMENT_BODY TRUE
J 0
(-6025 2150);
DISPLAY 0.872340 (-6025 2150);
PAINT GREEN (-6025 2150);
DISPLAY INVISIBLE (-6025 2150);
FORCEPROP 2 LAST PATH I58
J 0
(-6100 2325);
DISPLAY 1.021277 (-6100 2325);
PAINT ORANGE (-6100 2325);
DISPLAY INVISIBLE (-6100 2325);
FORCEADD OFFPAGE..1
(-6800 3475);
FORCEPROP 2 LAST $XR0 129 
J 0
(-7052 3475);
DISPLAY 0.638298 (-7052 3475);
PAINT MONO (-7052 3475);
FORCEPROP 2 LAST CDS_LIB mstr_standard
J 0
(-6800 3475);
PAINT MONO (-6800 3475);
DISPLAY INVISIBLE (-6800 3475);
FORCEPROP 1 LAST OFFPAGE TRUE
J 0
(-6475 3350);
DISPLAY 1.170213 (-6475 3350);
PAINT GREEN (-6475 3350);
DISPLAY INVISIBLE (-6475 3350);
FORCEPROP 1 LAST COMMENT_BODY TRUE
J 0
(-6675 3375);
DISPLAY 1.170213 (-6675 3375);
PAINT GREEN (-6675 3375);
DISPLAY INVISIBLE (-6675 3375);
FORCEPROP 2 LAST PATH I6
J 0
(-6750 3550);
DISPLAY 1.021277 (-6750 3550);
PAINT ORANGE (-6750 3550);
DISPLAY INVISIBLE (-6750 3550);
FORCEADD VCC_CORE..1
(-1075 2275);
FORCEPROP 3 LASTPIN (-1075 2225) SIG_NAME PVCCMCP_CPU0\g
J 0
(-1065 2235);
DISPLAY 0.659574 (-1065 2235);
PAINT MONO (-1065 2235);
DISPLAY INVISIBLE (-1065 2235);
FORCEPROP 1 LAST HDL_POWER PVCCMCP_CPU0
J 1
(-1075 2325);
DISPLAY 0.617021 (-1075 2325);
PAINT GREEN (-1075 2325);
FORCEPROP 2 LAST CDS_LIB mstr_symbols
J 0
(-1075 2275);
PAINT ORANGE (-1075 2275);
DISPLAY INVISIBLE (-1075 2275);
FORCEPROP 1 LAST PATH I60
J 0
(-1025 2300);
DISPLAY 0.872340 (-1025 2300);
PAINT AQUA (-1025 2300);
DISPLAY INVISIBLE (-1025 2300);
FORCEADD SKX_EXT_B..9
(-3925 2550);
FORCEPROP 1 LAST LOCATION U5D1
J 0
(-4825 3700);
DISPLAY 0.617021 (-4825 3700);
PAINT AQUA (-4825 3700);
FORCEPROP 1 LAST PART_NUMBER TBD
J 0
(-4825 1400);
DISPLAY 0.617021 (-4825 1400);
PAINT BLUE (-4825 1400);
FORCEPROP 1 LAST MATERIAL IC
J 0
(-4825 3650);
DISPLAY 0.617021 (-4825 3650);
PAINT SKYBLUE (-4825 3650);
FORCEPROP 2 LASTPIN (-2975 2150) $PN AR20
J 0
(-2965 2160);
DISPLAY 0.617021 (-2965 2160);
PAINT ORANGE (-2965 2160);
FORCEPROP 2 LASTPIN (-2975 2100) $PN AR22
J 0
(-2965 2110);
DISPLAY 0.617021 (-2965 2110);
PAINT ORANGE (-2965 2110);
FORCEPROP 2 LASTPIN (-2975 2000) $PN AR26
J 0
(-2965 2010);
DISPLAY 0.617021 (-2965 2010);
PAINT ORANGE (-2965 2010);
FORCEPROP 2 LASTPIN (-2975 1950) $PN AR62
J 0
(-2965 1960);
DISPLAY 0.617021 (-2965 1960);
PAINT ORANGE (-2965 1960);
FORCEPROP 2 LASTPIN (-2975 1900) $PN AT13
J 0
(-2965 1910);
DISPLAY 0.617021 (-2965 1910);
PAINT ORANGE (-2965 1910);
FORCEPROP 2 LASTPIN (-2975 1850) $PN AT23
J 0
(-2965 1860);
DISPLAY 0.617021 (-2965 1860);
PAINT ORANGE (-2965 1860);
FORCEPROP 2 LASTPIN (-2975 1800) $PN AT25
J 0
(-2965 1810);
DISPLAY 0.617021 (-2965 1810);
PAINT ORANGE (-2965 1810);
FORCEPROP 2 LASTPIN (-2975 1750) $PN AV77
J 0
(-2965 1760);
DISPLAY 0.617021 (-2965 1760);
PAINT ORANGE (-2965 1760);
FORCEPROP 2 LASTPIN (-2975 1700) $PN AW64
J 0
(-2965 1710);
DISPLAY 0.617021 (-2965 1710);
PAINT ORANGE (-2965 1710);
FORCEPROP 2 LASTPIN (-4875 2150) $PN AW76
J 2
(-4885 2160);
DISPLAY 0.617021 (-4885 2160);
PAINT ORANGE (-4885 2160);
FORCEPROP 2 LASTPIN (-4875 2100) $PN AY65
J 2
(-4885 2110);
DISPLAY 0.617021 (-4885 2110);
PAINT ORANGE (-4885 2110);
FORCEPROP 2 LASTPIN (-4875 2000) $PN AY67
J 2
(-4885 2010);
DISPLAY 0.617021 (-4885 2010);
PAINT ORANGE (-4885 2010);
FORCEPROP 2 LASTPIN (-4875 1950) $PN AY75
J 2
(-4885 1960);
DISPLAY 0.617021 (-4885 1960);
PAINT ORANGE (-4885 1960);
FORCEPROP 2 LASTPIN (-4875 1900) $PN AY77
J 2
(-4885 1910);
DISPLAY 0.617021 (-4885 1910);
PAINT ORANGE (-4885 1910);
FORCEPROP 2 LASTPIN (-4875 1850) $PN BA14
J 2
(-4885 1860);
DISPLAY 0.617021 (-4885 1860);
PAINT ORANGE (-4885 1860);
FORCEPROP 2 LASTPIN (-4875 1800) $PN BA16
J 2
(-4885 1810);
DISPLAY 0.617021 (-4885 1810);
PAINT ORANGE (-4885 1810);
FORCEPROP 2 LASTPIN (-4875 1750) $PN BA18
J 2
(-4885 1760);
DISPLAY 0.617021 (-4885 1760);
PAINT ORANGE (-4885 1760);
FORCEPROP 2 LASTPIN (-4875 1700) $PN BA22
J 2
(-4885 1710);
DISPLAY 0.617021 (-4885 1710);
PAINT ORANGE (-4885 1710);
FORCEPROP 2 LASTPIN (-4875 1650) $PN BA64
J 2
(-4885 1660);
DISPLAY 0.617021 (-4885 1660);
PAINT ORANGE (-4885 1660);
FORCEPROP 2 LASTPIN (-2975 1650) $PN BA66
J 0
(-2965 1660);
DISPLAY 0.617021 (-2965 1660);
PAINT ORANGE (-2965 1660);
FORCEPROP 2 LASTPIN (-2975 1600) $PN BA76
J 0
(-2965 1610);
DISPLAY 0.617021 (-2965 1610);
PAINT ORANGE (-2965 1610);
FORCEPROP 2 LASTPIN (-2975 3450) $PN CR4
J 0
(-2965 3460);
DISPLAY 0.617021 (-2965 3460);
PAINT ORANGE (-2965 3460);
FORCEPROP 2 LASTPIN (-2975 3400) $PN CM3
J 0
(-2965 3410);
DISPLAY 0.617021 (-2965 3410);
PAINT ORANGE (-2965 3410);
FORCEPROP 2 LASTPIN (-2975 3350) $PN CL4
J 0
(-2965 3360);
DISPLAY 0.617021 (-2965 3360);
PAINT ORANGE (-2965 3360);
FORCEPROP 2 LASTPIN (-2975 3300) $PN CH5
J 0
(-2965 3310);
DISPLAY 0.617021 (-2965 3310);
PAINT ORANGE (-2965 3310);
FORCEPROP 2 LASTPIN (-2975 3200) $PN CP5
J 0
(-2965 3210);
DISPLAY 0.617021 (-2965 3210);
PAINT ORANGE (-2965 3210);
FORCEPROP 2 LASTPIN (-2975 3150) $PN CN4
J 0
(-2965 3160);
DISPLAY 0.617021 (-2965 3160);
PAINT ORANGE (-2965 3160);
FORCEPROP 2 LASTPIN (-2975 3100) $PN CJ4
J 0
(-2965 3110);
DISPLAY 0.617021 (-2965 3110);
PAINT ORANGE (-2965 3110);
FORCEPROP 2 LASTPIN (-2975 3050) $PN CG4
J 0
(-2965 3060);
DISPLAY 0.617021 (-2965 3060);
PAINT ORANGE (-2965 3060);
FORCEPROP 2 LASTPIN (-4875 3450) $PN CV11
J 2
(-4885 3460);
DISPLAY 0.617021 (-4885 3460);
PAINT ORANGE (-4885 3460);
FORCEPROP 2 LASTPIN (-4875 3400) $PN CP11
J 2
(-4885 3410);
DISPLAY 0.617021 (-4885 3410);
PAINT ORANGE (-4885 3410);
FORCEPROP 2 LASTPIN (-4875 3350) $PN CN10
J 2
(-4885 3360);
DISPLAY 0.617021 (-4885 3360);
PAINT ORANGE (-4885 3360);
FORCEPROP 2 LASTPIN (-4875 3300) $PN CL10
J 2
(-4885 3310);
DISPLAY 0.617021 (-4885 3310);
PAINT ORANGE (-4885 3310);
FORCEPROP 2 LASTPIN (-4875 3200) $PN CT11
J 2
(-4885 3210);
DISPLAY 0.617021 (-4885 3210);
PAINT ORANGE (-4885 3210);
FORCEPROP 2 LASTPIN (-4875 3150) $PN CR12
J 2
(-4885 3160);
DISPLAY 0.617021 (-4885 3160);
PAINT ORANGE (-4885 3160);
FORCEPROP 2 LASTPIN (-4875 3100) $PN CM11
J 2
(-4885 3110);
DISPLAY 0.617021 (-4885 3110);
PAINT ORANGE (-4885 3110);
FORCEPROP 2 LASTPIN (-4875 3050) $PN CK9
J 2
(-4885 3060);
DISPLAY 0.617021 (-4885 3060);
PAINT ORANGE (-4885 3060);
FORCEPROP 2 LASTPIN (-4875 2250) $PN CD23
J 2
(-4885 2260);
DISPLAY 0.617021 (-4885 2260);
PAINT ORANGE (-4885 2260);
FORCEPROP 2 LASTPIN (-4875 2300) $PN CE24
J 2
(-4885 2310);
DISPLAY 0.617021 (-4885 2310);
PAINT ORANGE (-4885 2310);
FORCEPROP 2 LASTPIN (-2975 2250) $PN CC22
J 0
(-2965 2260);
DISPLAY 0.617021 (-2965 2260);
PAINT ORANGE (-2965 2260);
FORCEPROP 2 LASTPIN (-4875 2350) $PN BY21
J 2
(-4885 2360);
DISPLAY 0.617021 (-4885 2360);
PAINT ORANGE (-4885 2360);
FORCEPROP 2 LASTPIN (-4875 2400) $PN CB23
J 2
(-4885 2410);
DISPLAY 0.617021 (-4885 2410);
PAINT ORANGE (-4885 2410);
FORCEPROP 2 LASTPIN (-2975 2350) $PN CF25
J 0
(-2965 2360);
DISPLAY 0.617021 (-2965 2360);
PAINT ORANGE (-2965 2360);
FORCEPROP 2 LASTPIN (-2975 2950) $PN BW24
J 0
(-2965 2960);
DISPLAY 0.617021 (-2965 2960);
PAINT ORANGE (-2965 2960);
FORCEPROP 2 LASTPIN (-2975 2900) $PN BU24
J 0
(-2965 2910);
DISPLAY 0.617021 (-2965 2910);
PAINT ORANGE (-2965 2910);
FORCEPROP 2 LASTPIN (-4875 2950) $PN BG16
J 2
(-4885 2960);
DISPLAY 0.617021 (-4885 2960);
PAINT ORANGE (-4885 2960);
FORCEPROP 2 LASTPIN (-4875 2900) $PN BE16
J 2
(-4885 2910);
DISPLAY 0.617021 (-4885 2910);
PAINT ORANGE (-4885 2910);
FORCEPROP 2 LASTPIN (-2975 2800) $PN BK23
J 0
(-2965 2810);
DISPLAY 0.617021 (-2965 2810);
PAINT ORANGE (-2965 2810);
FORCEPROP 2 LASTPIN (-2975 2750) $PN BT19
J 0
(-2965 2760);
DISPLAY 0.617021 (-2965 2760);
PAINT ORANGE (-2965 2760);
FORCEPROP 2 LASTPIN (-2975 2700) $PN BM23
J 0
(-2965 2710);
DISPLAY 0.617021 (-2965 2710);
PAINT ORANGE (-2965 2710);
FORCEPROP 2 LASTPIN (-2975 2650) $PN BM21
J 0
(-2965 2660);
DISPLAY 0.617021 (-2965 2660);
PAINT ORANGE (-2965 2660);
FORCEPROP 2 LASTPIN (-2975 2500) $PN BH23
J 0
(-2965 2510);
DISPLAY 0.617021 (-2965 2510);
PAINT ORANGE (-2965 2510);
FORCEPROP 2 LASTPIN (-2975 2550) $PN BJ22
J 0
(-2965 2560);
DISPLAY 0.617021 (-2965 2560);
PAINT ORANGE (-2965 2560);
FORCEPROP 2 LASTPIN (-4875 2800) $PN BN24
J 2
(-4885 2810);
DISPLAY 0.617021 (-4885 2810);
PAINT ORANGE (-4885 2810);
FORCEPROP 2 LASTPIN (-4875 2750) $PN BR20
J 2
(-4885 2760);
DISPLAY 0.617021 (-4885 2760);
PAINT ORANGE (-4885 2760);
FORCEPROP 2 LASTPIN (-4875 2700) $PN BK21
J 2
(-4885 2710);
DISPLAY 0.617021 (-4885 2710);
PAINT ORANGE (-4885 2710);
FORCEPROP 2 LASTPIN (-4875 2650) $PN BP19
J 2
(-4885 2660);
DISPLAY 0.617021 (-4885 2660);
PAINT ORANGE (-4885 2660);
FORCEPROP 2 LASTPIN (-4875 2500) $PN BP23
J 2
(-4885 2510);
DISPLAY 0.617021 (-4885 2510);
PAINT ORANGE (-4885 2510);
FORCEPROP 2 LASTPIN (-4875 2550) $PN BN22
J 2
(-4885 2560);
DISPLAY 0.617021 (-4885 2560);
PAINT ORANGE (-4885 2560);
FORCEPROP 1 LAST PACK_TYPE BGA1
J 0
(-4825 3750);
PAINT SKYBLUE (-4825 3750);
DISPLAY INVISIBLE (-4825 3750);
FORCEPROP 2 LAST CDS_LIB chpset_lib
J 0
(-3925 2550);
PAINT ORANGE (-3925 2550);
DISPLAY INVISIBLE (-3925 2550);
FORCEPROP 2 LAST SEC_TYPE BGA1
J 0
(-4825 3750);
DISPLAY 1.021277 (-4825 3750);
PAINT ORANGE (-4825 3750);
DISPLAY INVISIBLE (-4825 3750);
FORCEPROP 2 LAST SEC 9
J 0
(-4825 3750);
DISPLAY 0.680851 (-4825 3750);
PAINT MONO (-4825 3750);
DISPLAY INVISIBLE (-4825 3750);
FORCEPROP 2 LAST CDS_LOCATION U5D1
J 0
(-4825 3700);
DISPLAY 0.617021 (-4825 3700);
PAINT AQUA (-4825 3700);
DISPLAY INVISIBLE (-4825 3700);
FORCEPROP 1 LAST PATH I61
J 0
(-3925 3650);
PAINT GREEN (-3925 3650);
DISPLAY INVISIBLE (-3925 3650);
FORCEPROP 0 LAST ROOM CPU0
J 0
(-4825 3800);
DISPLAY 1.021277 (-4825 3800);
PAINT ORANGE (-4825 3800);
DISPLAY INVISIBLE (-4825 3800);
FORCEADD TAP..1
R 2
(-5425 3050);
FORCEPROP 3 LASTPIN (-5375 3050) SIG_NAME DMI_CPU0_PCH_RX_C_DN<0>
J 0
(-5365 3060);
DISPLAY 0.659574 (-5365 3060);
PAINT MONO (-5365 3060);
DISPLAY INVISIBLE (-5365 3060);
FORCEPROP 1 LASTPIN (-5375 3050) BN 0
J 2
(-5363 3058);
DISPLAY 0.617021 (-5363 3058);
PAINT PINK (-5363 3058);
FORCEPROP 2 LAST CDS_LIB mstr_standard
J 0
(-5425 3050);
PAINT MONO (-5425 3050);
DISPLAY INVISIBLE (-5425 3050);
FORCEPROP 1 LAST BODY_TYPE PLUMBING
J 2
(-5425 3100);
DISPLAY 1.446809 (-5425 3100);
PAINT GREEN (-5425 3100);
DISPLAY INVISIBLE (-5425 3100);
FORCEPROP 1 LAST HDL_TAP TRUE
J 2
(-5750 2925);
DISPLAY 1.446809 (-5750 2925);
PAINT GREEN (-5750 2925);
DISPLAY INVISIBLE (-5750 2925);
FORCEPROP 1 LAST PATH I7
J 2
(-5423 3050);
DISPLAY 0.872340 (-5423 3050);
PAINT GREEN (-5423 3050);
DISPLAY INVISIBLE (-5423 3050);
FORCEADD TAP..1
R 2
(-5425 3100);
FORCEPROP 3 LASTPIN (-5375 3100) SIG_NAME DMI_CPU0_PCH_RX_C_DN<1>
J 0
(-5365 3110);
DISPLAY 0.659574 (-5365 3110);
PAINT MONO (-5365 3110);
DISPLAY INVISIBLE (-5365 3110);
FORCEPROP 1 LASTPIN (-5375 3100) BN 1
J 2
(-5363 3108);
DISPLAY 0.617021 (-5363 3108);
PAINT PINK (-5363 3108);
FORCEPROP 2 LAST CDS_LIB mstr_standard
J 0
(-5425 3100);
PAINT MONO (-5425 3100);
DISPLAY INVISIBLE (-5425 3100);
FORCEPROP 1 LAST BODY_TYPE PLUMBING
J 2
(-5425 3150);
DISPLAY 1.446809 (-5425 3150);
PAINT GREEN (-5425 3150);
DISPLAY INVISIBLE (-5425 3150);
FORCEPROP 1 LAST HDL_TAP TRUE
J 2
(-5750 2975);
DISPLAY 1.446809 (-5750 2975);
PAINT GREEN (-5750 2975);
DISPLAY INVISIBLE (-5750 2975);
FORCEPROP 1 LAST PATH I8
J 2
(-5423 3100);
DISPLAY 0.872340 (-5423 3100);
PAINT GREEN (-5423 3100);
DISPLAY INVISIBLE (-5423 3100);
FORCEADD TAP..1
R 2
(-5425 3200);
FORCEPROP 3 LASTPIN (-5375 3200) SIG_NAME DMI_CPU0_PCH_RX_C_DN<3>
J 0
(-5365 3210);
DISPLAY 0.659574 (-5365 3210);
PAINT MONO (-5365 3210);
DISPLAY INVISIBLE (-5365 3210);
FORCEPROP 1 LASTPIN (-5375 3200) BN 3
J 2
(-5363 3208);
DISPLAY 0.617021 (-5363 3208);
PAINT PINK (-5363 3208);
FORCEPROP 2 LAST CDS_LIB mstr_standard
J 0
(-5425 3200);
PAINT MONO (-5425 3200);
DISPLAY INVISIBLE (-5425 3200);
FORCEPROP 1 LAST BODY_TYPE PLUMBING
J 2
(-5425 3250);
DISPLAY 1.446809 (-5425 3250);
PAINT GREEN (-5425 3250);
DISPLAY INVISIBLE (-5425 3250);
FORCEPROP 1 LAST HDL_TAP TRUE
J 2
(-5750 3075);
DISPLAY 1.446809 (-5750 3075);
PAINT GREEN (-5750 3075);
DISPLAY INVISIBLE (-5750 3075);
FORCEPROP 1 LAST PATH I9
J 2
(-5423 3200);
DISPLAY 0.872340 (-5423 3200);
PAINT GREEN (-5423 3200);
DISPLAY INVISIBLE (-5423 3200);
FORCEADD PRELIM..10
(-3890 2590);
PAINT GRAY (-3890 2590);
FORCEPROP 2 LAST CDS_LIB mstr_misc
J 0
(-3890 2590);
PAINT ORANGE (-3890 2590);
DISPLAY INVISIBLE (-3890 2590);
FORCEPROP 1 LAST COMMENT_BODY TRUE
J 0
(-3890 2590);
PAINT ORANGE (-3890 2590);
DISPLAY INVISIBLE (-3890 2590);
FORCEADD DESIGN_NOTE..1
(-4625 1250);
FORCEPROP 0 LAST L1 CPU SYMBOLS 1-30 ARE PRELIMINARY AND SUBJECT TO CHANGE
J 0
(-4825 1125);
DISPLAY 1.021277 (-4825 1125);
PAINT ORANGE (-4825 1125);
FORCEPROP 2 LAST CDS_LIB mstr_symbols
J 0
(-4625 1250);
PAINT ORANGE (-4625 1250);
DISPLAY INVISIBLE (-4625 1250);
FORCEPROP 1 LAST COMMENT_BODY TRUE
J 0
(-4600 1350);
DISPLAY 0.978723 (-4600 1350);
PAINT ORANGE (-4600 1350);
DISPLAY INVISIBLE (-4600 1350);
FORCEADD INTEL_CORP_BPAGE..1
(0 0);
FORCEPROP 1 LAST CDS_CON_LAST_MODIFIED Tue Dec 01 11:51:20 2015
J 0
(-1425 325);
DISPLAY 1.340426 (-1425 325);
PAINT GREEN (-1425 325);
DISPLAY INVISIBLE (-1425 325);
FORCEPROP 1 LAST CUSTOM_TXT_CDS <CURRENT_DESIGN_SHEET> OF <TOTAL_DESIGN_SHEETS>
J 0
(-500 25);
PAINT GREEN (-500 25);
FORCEPROP 1 LAST CUSTOM_TXT_CDS <CON_LAST_MODIFIED>
J 0
(-1925 350);
PAINT GREEN (-1925 350);
FORCEPROP 2 LAST CUSTOM_TXT_CDS <XR_PAGE_TITLE>
J 0
(-7890 5250);
DISPLAY 0.638298 (-7890 5250);
PAINT PINK (-7890 5250);
DISPLAY INVISIBLE (-7890 5250);
FORCEPROP 1 LAST SCH_ADDRESS3 Santa Clara, CA 95052-8119
J 0
(-3975 25);
DISPLAY 0.617021 (-3975 25);
PAINT GREEN (-3975 25);
FORCEPROP 1 LAST SCH_ADDRESS2 P.O. BOX 58119
J 0
(-3975 75);
DISPLAY 0.617021 (-3975 75);
PAINT GREEN (-3975 75);
FORCEPROP 1 LAST SCH_ADDRESS1 2200 Mission College Blvd.
J 0
(-3975 125);
DISPLAY 0.617021 (-3975 125);
PAINT GREEN (-3975 125);
FORCEPROP 1 LAST SCH_TITLE SKYLAKE - SKT0 - 9 OF 21
J 0
(-7950 50);
DISPLAY 1.212766 (-7950 50);
PAINT GREEN (-7950 50);
FORCEPROP 1 LAST SCH_NUMBER H4694802
J 0
(-1300 150);
DISPLAY 1.212766 (-1300 150);
PAINT YELLOW (-1300 150);
FORCEPROP 1 LAST SCH_DEPT BESD
J 1
(-4450 100);
DISPLAY 1.212766 (-4450 100);
PAINT YELLOW (-4450 100);
FORCEPROP 1 LAST SCH_REV 2.420
J 0
(-250 150);
DISPLAY 0.978723 (-250 150);
PAINT YELLOW (-250 150);
FORCEPROP 2 LAST CDS_LIB mstr_symbols
J 0
(0 0);
PAINT ORANGE (0 0);
DISPLAY INVISIBLE (0 0);
FORCEPROP 2 LAST PAGE_BORDER TRUE
J 0
(-7890 5250);
DISPLAY 0.851064 (-7890 5250);
PAINT PINK (-7890 5250);
DISPLAY INVISIBLE (-7890 5250);
FORCEPROP 1 LAST COMMENT_BODY TRUE
J 0
(12 12);
DISPLAY 0.638298 (12 12);
PAINT GREEN (12 12);
DISPLAY INVISIBLE (12 12);
FORCEPROP 2 LAST CDS_XR_PAGE_TITLE CR-29 : @BASEBOARD_FAB2_LIB.BASEBOARD_FAB2(SCH_1):PAGE29
J 0
(-7890 5250);
DISPLAY 0.638298 (-7890 5250);
PAINT PINK (-7890 5250);
DISPLAY INVISIBLE (-7890 5250);
WIRE 17 -1 (-2300 3175)(-2300 3225);
WIRE 17 -1 (-2300 3125)(-2300 3175);
WIRE 17 -1 (-2300 3225)(-1050 3225);
FORCEPROP 2 LAST SIG_NAME DMI_CPU0_PCH_TX_DN<3:0>
J 0
(-2210 3235);
DISPLAY 0.617021 (-2210 3235);
PAINT ORANGE (-2210 3235);
WIRE 17 -1 (-2300 3075)(-2300 3125);
WIRE 17 -1 (-2300 3425)(-2300 3475);
WIRE 17 -1 (-2300 3375)(-2300 3425);
WIRE 17 -1 (-2300 3475)(-1050 3475);
FORCEPROP 2 LAST SIG_NAME DMI_CPU0_PCH_TX_DP<3:0>
J 0
(-2210 3485);
DISPLAY 0.617021 (-2210 3485);
PAINT ORANGE (-2210 3485);
WIRE 17 -1 (-2300 3325)(-2300 3375);
WIRE 17 -1 (-5475 3225)(-5475 3175);
WIRE 17 -1 (-6750 3225)(-5475 3225);
FORCEPROP 2 LAST SIG_NAME DMI_CPU0_PCH_RX_C_DN<3:0>
J 0
(-6710 3235);
DISPLAY 0.617021 (-6710 3235);
PAINT ORANGE (-6710 3235);
WIRE 17 -1 (-5475 3175)(-5475 3125);
WIRE 17 -1 (-5475 3125)(-5475 3075);
WIRE 17 -1 (-5475 3475)(-5475 3425);
WIRE 17 -1 (-6750 3475)(-5475 3475);
FORCEPROP 2 LAST SIG_NAME DMI_CPU0_PCH_RX_C_DP<3:0>
J 0
(-6710 3485);
DISPLAY 0.617021 (-6710 3485);
PAINT ORANGE (-6710 3485);
WIRE 17 -1 (-5475 3425)(-5475 3375);
WIRE 17 -1 (-5475 3375)(-5475 3325);
WIRE 16 -1 (-2975 2000)(-2800 2000);
WIRE 16 -1 (-2800 2000)(-2800 2100);
WIRE 16 -1 (-2975 2100)(-2800 2100);
WIRE 16 -1 (-2800 2100)(-2800 2150);
WIRE 16 -1 (-2975 2150)(-2800 2150);
WIRE 16 -1 (-2800 2150)(-1075 2150);
WIRE 16 -1 (-1075 1850)(-1075 2150);
WIRE 16 -1 (-1075 2150)(-1075 2225);
WIRE 16 -1 (-2850 1850)(-1075 1850);
WIRE 16 -1 (-2850 1800)(-2850 1850);
WIRE 16 -1 (-2975 1850)(-2850 1850);
WIRE 16 -1 (-2975 1800)(-2850 1800);
WIRE 16 -1 (-4875 1650)(-5675 1650);
FORCEPROP 2 LAST SIG_NAME TP_CPU0_RSVD_174
J 0
(-5650 1660);
DISPLAY 0.617021 (-5650 1660);
PAINT ORANGE (-5650 1660);
FORCEPROP 2 LASTPROP $XRERR UNIQUE?
J 0
(-5915 1650);
DISPLAY 0.638298 (-5915 1650);
PAINT MONO (-5915 1650);
DISPLAY INVISIBLE (-5915 1650);
WIRE 16 -1 (-4875 1700)(-5675 1700);
FORCEPROP 2 LAST SIG_NAME TP_CPU0_RSVD_175
J 0
(-5650 1710);
DISPLAY 0.617021 (-5650 1710);
PAINT ORANGE (-5650 1710);
FORCEPROP 2 LASTPROP $XRERR UNIQUE?
J 0
(-5915 1700);
DISPLAY 0.638298 (-5915 1700);
PAINT MONO (-5915 1700);
DISPLAY INVISIBLE (-5915 1700);
WIRE 16 -1 (-4875 1750)(-5675 1750);
FORCEPROP 2 LAST SIG_NAME TP_CPU0_RSVD_176
J 0
(-5650 1760);
DISPLAY 0.617021 (-5650 1760);
PAINT ORANGE (-5650 1760);
FORCEPROP 2 LASTPROP $XRERR UNIQUE?
J 0
(-5915 1750);
DISPLAY 0.638298 (-5915 1750);
PAINT MONO (-5915 1750);
DISPLAY INVISIBLE (-5915 1750);
WIRE 16 -1 (-4875 1800)(-5675 1800);
FORCEPROP 2 LAST SIG_NAME TP_CPU0_RSVD_177
J 0
(-5650 1810);
DISPLAY 0.617021 (-5650 1810);
PAINT ORANGE (-5650 1810);
FORCEPROP 2 LASTPROP $XRERR UNIQUE?
J 0
(-5915 1800);
DISPLAY 0.638298 (-5915 1800);
PAINT MONO (-5915 1800);
DISPLAY INVISIBLE (-5915 1800);
WIRE 16 -1 (-4875 1850)(-5675 1850);
FORCEPROP 2 LAST SIG_NAME TP_CPU0_RSVD_178
J 0
(-5650 1860);
DISPLAY 0.617021 (-5650 1860);
PAINT ORANGE (-5650 1860);
FORCEPROP 2 LASTPROP $XRERR UNIQUE?
J 0
(-5915 1850);
DISPLAY 0.638298 (-5915 1850);
PAINT MONO (-5915 1850);
DISPLAY INVISIBLE (-5915 1850);
WIRE 16 -1 (-4875 2000)(-5675 2000);
FORCEPROP 2 LAST SIG_NAME TP_CPU0_RSVD_181
J 0
(-5650 2010);
DISPLAY 0.617021 (-5650 2010);
PAINT ORANGE (-5650 2010);
FORCEPROP 2 LASTPROP $XRERR UNIQUE?
J 0
(-5915 2000);
DISPLAY 0.638298 (-5915 2000);
PAINT MONO (-5915 2000);
DISPLAY INVISIBLE (-5915 2000);
WIRE 16 -1 (-4875 1900)(-5675 1900);
FORCEPROP 2 LAST SIG_NAME TP_CPU0_RSVD_179
J 0
(-5650 1910);
DISPLAY 0.617021 (-5650 1910);
PAINT ORANGE (-5650 1910);
FORCEPROP 2 LASTPROP $XRERR UNIQUE?
J 0
(-5915 1900);
DISPLAY 0.638298 (-5915 1900);
PAINT MONO (-5915 1900);
DISPLAY INVISIBLE (-5915 1900);
WIRE 16 -1 (-4875 1950)(-5675 1950);
FORCEPROP 2 LAST SIG_NAME TP_CPU0_RSVD_180
J 0
(-5650 1960);
DISPLAY 0.617021 (-5650 1960);
PAINT ORANGE (-5650 1960);
FORCEPROP 2 LASTPROP $XRERR UNIQUE?
J 0
(-5915 1950);
DISPLAY 0.638298 (-5915 1950);
PAINT MONO (-5915 1950);
DISPLAY INVISIBLE (-5915 1950);
WIRE 16 -1 (-4875 3300)(-5375 3300);
WIRE 16 -1 (-5375 3350)(-4875 3350);
WIRE 16 -1 (-5375 3400)(-4875 3400);
WIRE 16 -1 (-5375 3450)(-4875 3450);
WIRE 16 -1 (-4875 3050)(-5375 3050);
WIRE 16 -1 (-4875 3100)(-5375 3100);
WIRE 16 -1 (-5375 3150)(-4875 3150);
WIRE 16 -1 (-4875 3200)(-5375 3200);
WIRE 16 -1 (-4875 2100)(-5675 2100);
FORCEPROP 2 LAST SIG_NAME TP_CPU0_RSVD_182
J 0
(-5650 2110);
DISPLAY 0.617021 (-5650 2110);
PAINT ORANGE (-5650 2110);
FORCEPROP 2 LASTPROP $XRERR UNIQUE?
J 0
(-5915 2100);
DISPLAY 0.638298 (-5915 2100);
PAINT MONO (-5915 2100);
DISPLAY INVISIBLE (-5915 2100);
WIRE 16 -1 (-4875 2150)(-5675 2150);
FORCEPROP 2 LAST SIG_NAME TP_CPU0_RSVD_183
J 0
(-5650 2160);
DISPLAY 0.617021 (-5650 2160);
PAINT ORANGE (-5650 2160);
FORCEPROP 2 LASTPROP $XRERR UNIQUE?
J 0
(-5915 2150);
DISPLAY 0.638298 (-5915 2150);
PAINT MONO (-5915 2150);
DISPLAY INVISIBLE (-5915 2150);
WIRE 16 -1 (-6100 2400)(-4875 2400);
FORCEPROP 2 LAST SIG_NAME JTAG_MCP_TCK
J 0
(-6060 2410);
DISPLAY 0.617021 (-6060 2410);
PAINT ORANGE (-6060 2410);
WIRE 16 -1 (-4875 2350)(-6100 2350);
FORCEPROP 2 LAST SIG_NAME JTAG_MCP_CPU0_TDI
J 0
(-6060 2360);
DISPLAY 0.617021 (-6060 2360);
PAINT ORANGE (-6060 2360);
WIRE 16 -1 (-4875 2300)(-6100 2300);
FORCEPROP 2 LAST SIG_NAME JTAG_MCP_TMS
J 0
(-6060 2310);
DISPLAY 0.617021 (-6060 2310);
PAINT ORANGE (-6060 2310);
WIRE 16 -1 (-4875 2950)(-6100 2950);
FORCEPROP 2 LAST SIG_NAME CLK_156M_OSC_CPU0_HFI_DP
J 0
(-6010 2960);
DISPLAY 0.617021 (-6010 2960);
PAINT ORANGE (-6010 2960);
WIRE 16 -1 (-6100 2900)(-4875 2900);
FORCEPROP 2 LAST SIG_NAME CLK_156M_OSC_CPU0_HFI_DN
J 0
(-6010 2910);
DISPLAY 0.617021 (-6010 2910);
PAINT ORANGE (-6010 2910);
WIRE 16 -1 (-4875 2800)(-6125 2800);
FORCEPROP 2 LAST SIG_NAME RST_HFI0_CPU0_LVT2_N
J 0
(-6075 2810);
DISPLAY 0.617021 (-6075 2810);
PAINT ORANGE (-6075 2810);
WIRE 16 -1 (-4875 2750)(-6125 2750);
FORCEPROP 2 LAST SIG_NAME FM_MODPRST_HFI0_CPU0_LVT2_N
J 0
(-6075 2760);
DISPLAY 0.617021 (-6075 2760);
PAINT ORANGE (-6075 2760);
WIRE 16 -1 (-6125 2650)(-4875 2650);
FORCEPROP 2 LAST SIG_NAME IRQ_HFI0_CPU0_LVT2_N
J 0
(-6075 2660);
DISPLAY 0.617021 (-6075 2660);
PAINT ORANGE (-6075 2660);
WIRE 16 -1 (-6125 2700)(-4875 2700);
FORCEPROP 2 LAST SIG_NAME LED_HFI0_CPU0_N
J 0
(-6075 2710);
DISPLAY 0.617021 (-6075 2710);
PAINT ORANGE (-6075 2710);
WIRE 16 -1 (-6125 2550)(-4875 2550);
FORCEPROP 2 LAST SIG_NAME SMB_HFI0_CPU0_LVC2_SCL
J 0
(-6075 2560);
DISPLAY 0.617021 (-6075 2560);
PAINT ORANGE (-6075 2560);
WIRE 16 -1 (-4875 2500)(-6125 2500);
FORCEPROP 2 LAST SIG_NAME SMB_HFI0_CPU0_LVC2_SDA
J 0
(-6075 2510);
DISPLAY 0.617021 (-6075 2510);
PAINT ORANGE (-6075 2510);
WIRE 16 -1 (-4875 2250)(-6100 2250);
FORCEPROP 2 LAST SIG_NAME JTAG_MCP_TRST_N
J 0
(-6060 2260);
DISPLAY 0.617021 (-6060 2260);
PAINT ORANGE (-6060 2260);
WIRE 16 -1 (-2175 1600)(-2975 1600);
FORCEPROP 2 LAST SIG_NAME TP_CPU0_RSVD_172
J 0
(-2700 1610);
DISPLAY 0.617021 (-2700 1610);
PAINT ORANGE (-2700 1610);
FORCEPROP 2 LASTPROP $XRERR UNIQUE?
J 0
(-2145 1600);
DISPLAY 0.638298 (-2145 1600);
PAINT MONO (-2145 1600);
DISPLAY INVISIBLE (-2145 1600);
WIRE 16 -1 (-2175 1650)(-2975 1650);
FORCEPROP 2 LAST SIG_NAME TP_CPU0_RSVD_173
J 0
(-2700 1660);
DISPLAY 0.617021 (-2700 1660);
PAINT ORANGE (-2700 1660);
FORCEPROP 2 LASTPROP $XRERR UNIQUE?
J 0
(-2145 1650);
DISPLAY 0.638298 (-2145 1650);
PAINT MONO (-2145 1650);
DISPLAY INVISIBLE (-2145 1650);
WIRE 16 -1 (-2175 1700)(-2975 1700);
FORCEPROP 2 LAST SIG_NAME TP_CPU0_RSVD_184
J 0
(-2700 1710);
DISPLAY 0.617021 (-2700 1710);
PAINT ORANGE (-2700 1710);
FORCEPROP 2 LASTPROP $XRERR UNIQUE?
J 0
(-2145 1700);
DISPLAY 0.638298 (-2145 1700);
PAINT MONO (-2145 1700);
DISPLAY INVISIBLE (-2145 1700);
WIRE 16 -1 (-2175 1750)(-2975 1750);
FORCEPROP 2 LAST SIG_NAME TP_CPU0_RSVD_186
J 0
(-2700 1760);
DISPLAY 0.617021 (-2700 1760);
PAINT ORANGE (-2700 1760);
FORCEPROP 2 LASTPROP $XRERR UNIQUE?
J 0
(-2145 1750);
DISPLAY 0.638298 (-2145 1750);
PAINT MONO (-2145 1750);
DISPLAY INVISIBLE (-2145 1750);
WIRE 16 -1 (-2175 1900)(-2975 1900);
FORCEPROP 2 LAST SIG_NAME TP_CPU0_RSVD_189
J 0
(-2700 1910);
DISPLAY 0.617021 (-2700 1910);
PAINT ORANGE (-2700 1910);
FORCEPROP 2 LASTPROP $XRERR UNIQUE?
J 0
(-2145 1900);
DISPLAY 0.638298 (-2145 1900);
PAINT MONO (-2145 1900);
DISPLAY INVISIBLE (-2145 1900);
WIRE 16 -1 (-2175 1950)(-2975 1950);
FORCEPROP 2 LAST SIG_NAME TP_CPU0_RSVD_190
J 0
(-2700 1960);
DISPLAY 0.617021 (-2700 1960);
PAINT ORANGE (-2700 1960);
FORCEPROP 2 LASTPROP $XRERR UNIQUE?
J 0
(-2145 1950);
DISPLAY 0.638298 (-2145 1950);
PAINT MONO (-2145 1950);
DISPLAY INVISIBLE (-2145 1950);
WIRE 16 -1 (-2400 3050)(-2975 3050);
WIRE 16 -1 (-2400 3300)(-2975 3300);
WIRE 16 -1 (-2400 3350)(-2975 3350);
WIRE 16 -1 (-2975 3400)(-2400 3400);
WIRE 16 -1 (-2400 3450)(-2975 3450);
WIRE 16 -1 (-2400 3100)(-2975 3100);
WIRE 16 -1 (-2400 3150)(-2975 3150);
WIRE 16 -1 (-2400 3200)(-2975 3200);
WIRE 16 -1 (-1875 2250)(-2975 2250);
FORCEPROP 2 LAST SIG_NAME JTAG_MCP_CPU0_TDO
J 0
(-2710 2260);
DISPLAY 0.617021 (-2710 2260);
PAINT ORANGE (-2710 2260);
WIRE 16 -1 (-1850 2950)(-2975 2950);
FORCEPROP 2 LAST SIG_NAME CLK_100M_CPU0_PE_REFCLK_DP
J 0
(-2750 2960);
DISPLAY 0.617021 (-2750 2960);
PAINT ORANGE (-2750 2960);
WIRE 16 -1 (-1850 2900)(-2975 2900);
FORCEPROP 2 LAST SIG_NAME CLK_100M_CPU0_PE_REFCLK_DN
J 0
(-2750 2910);
DISPLAY 0.617021 (-2750 2910);
PAINT ORANGE (-2750 2910);
WIRE 16 -1 (-1900 2350)(-2975 2350);
FORCEPROP 2 LAST SIG_NAME RST_CD_CPU0_POR_N
J 0
(-2700 2360);
DISPLAY 0.617021 (-2700 2360);
PAINT ORANGE (-2700 2360);
WIRE 16 -1 (-1850 2750)(-2975 2750);
FORCEPROP 2 LAST SIG_NAME FM_MODPRST_HFI1_CPU0_LVT2_N
J 0
(-2825 2760);
DISPLAY 0.617021 (-2825 2760);
PAINT ORANGE (-2825 2760);
WIRE 16 -1 (-1850 2650)(-2975 2650);
FORCEPROP 2 LAST SIG_NAME IRQ_HFI1_CPU0_LVT2_N
J 0
(-2825 2660);
DISPLAY 0.617021 (-2825 2660);
PAINT ORANGE (-2825 2660);
WIRE 16 -1 (-1850 2800)(-2975 2800);
FORCEPROP 2 LAST SIG_NAME RST_HFI1_CPU0_LVT2_N
J 0
(-2825 2810);
DISPLAY 0.617021 (-2825 2810);
PAINT ORANGE (-2825 2810);
WIRE 16 -1 (-1850 2700)(-2975 2700);
FORCEPROP 2 LAST SIG_NAME LED_HFI1_CPU0_N
J 0
(-2825 2710);
DISPLAY 0.617021 (-2825 2710);
PAINT ORANGE (-2825 2710);
WIRE 16 -1 (-1850 2550)(-2975 2550);
FORCEPROP 2 LAST SIG_NAME SMB_HFI1_CPU0_LVC2_SCL
J 0
(-2825 2560);
DISPLAY 0.617021 (-2825 2560);
PAINT ORANGE (-2825 2560);
WIRE 16 -1 (-1850 2500)(-2975 2500);
FORCEPROP 2 LAST SIG_NAME SMB_HFI1_CPU0_LVC2_SDA
J 0
(-2825 2510);
DISPLAY 0.617021 (-2825 2510);
PAINT ORANGE (-2825 2510);
DOT 1 (-1075 2150);
DOT 1 (-2800 2150);
DOT 1 (-2800 2100);
DOT 1 (-2850 1850);
FORCENOTE
BOM_COST=PROC_SOCKET
(-7925 250) 0;
DISPLAY LEFT (-7925 250);
DISPLAY 1.382979 (-7925 250);
PAINT PURPLE (-7925 250);
FORCENOTE
ROOM=CPU0
(-7925 375) 0;
DISPLAY LEFT (-7925 375);
DISPLAY 1.382979 (-7925 375);
PAINT PURPLE (-7925 375);
QUIT
